(kicad_pcb
	(version 20241229)
	(generator "pcbnew")
	(generator_version "9.0")
	(general
		(thickness 1.294)
		(legacy_teardrops no)
	)
	(paper "A3")
	(title_block
		(title "Kintex 410T devboard")
		(date "2024-04-03")
		(rev "1.1.2")
		(comment 9 "footprints 171-175 of 975")
	)
	(layers
		(0 "F.Cu" mixed)
		(4 "In1.Cu" power)
		(6 "In2.Cu" power)
		(8 "In3.Cu" mixed)
		(10 "In4.Cu" power)
		(12 "In5.Cu" mixed)
		(14 "In6.Cu" power)
		(16 "In7.Cu" mixed)
		(18 "In8.Cu" power)
		(2 "B.Cu" mixed)
		(9 "F.Adhes" user "F.Adhesive")
		(11 "B.Adhes" user "B.Adhesive")
		(13 "F.Paste" user)
		(15 "B.Paste" user)
		(5 "F.SilkS" user "F.Silkscreen")
		(7 "B.SilkS" user "B.Silkscreen")
		(1 "F.Mask" user)
		(3 "B.Mask" user)
		(17 "Dwgs.User" user "User.Drawings")
		(19 "Cmts.User" user "User.Comments")
		(21 "Eco1.User" user "User.Eco1")
		(23 "Eco2.User" user "User.Eco2")
		(25 "Edge.Cuts" user)
		(27 "Margin" user)
		(31 "F.CrtYd" user "F.Courtyard")
		(29 "B.CrtYd" user "B.Courtyard")
		(35 "F.Fab" user)
		(33 "B.Fab" user)
	)
	(footprint "antmicro-footprints:R_0402_1005Metric"
		(layer "F.Cu")
		(at 235.915 117.5 180)
		(descr "Resistor SMD 0402")
		(tags "resistor SMD 0402")
		(property "Reference" "R64"
			(at -0.735 -0.35 180)
			(layer "F.SilkS")
			(effects
				(font
					(size 0.7 0.7)
					(thickness 0.15)
				)
				(justify left bottom)
			)
		)
		(property "Value" "R_10k_0402"
			(at 0 1.4 180)
			(layer "F.Fab")
			(effects
				(font
					(size 0.7 0.7)
					(thickness 0.15)
				)
				(justify left bottom)
			)
		)
		(property "Description" "SMD Chip Resistor, 10 kohm, ± 1%, 62.5 mW, 0402 [1005 Metric], Thick Film, General Purpose"
			(at 0 0 180)
			(layer "F.Fab")
			(hide yes)
			(effects
				(font
					(size 1.27 1.27)
					(thickness 0.15)
				)
			)
		)
		(property "Author" "Antmicro"
			(at 471.83 235 0)
			(layer "F.Fab")
			(hide yes)
			(effects
				(font
					(size 1 1)
					(thickness 0.15)
				)
			)
		)
		(property "License" "Apache-2.0"
			(at 471.83 235 0)
			(layer "F.Fab")
			(hide yes)
			(effects
				(font
					(size 1 1)
					(thickness 0.15)
				)
			)
		)
		(property "MPN" "CR0402-FX-1002GLF"
			(at 471.83 235 0)
			(layer "F.Fab")
			(hide yes)
			(effects
				(font
					(size 1 1)
					(thickness 0.15)
				)
			)
		)
		(property "Manufacturer" "Bourns"
			(at 471.83 235 0)
			(layer "F.Fab")
			(hide yes)
			(effects
				(font
					(size 1 1)
					(thickness 0.15)
				)
			)
		)
		(property "Tolerance" "1%"
			(at 471.83 235 0)
			(layer "F.Fab")
			(hide yes)
			(effects
				(font
					(size 1 1)
					(thickness 0.15)
				)
			)
		)
		(property "Val" "10k"
			(at 471.83 235 0)
			(layer "F.Fab")
			(hide yes)
			(effects
				(font
					(size 1 1)
					(thickness 0.15)
				)
			)
		)
		(sheetname "SPI Flash + SD Card")
		(sheetfile "spi-flash.kicad_sch")
		(attr smd)
		(fp_rect
			(start -0.925 -0.47)
			(end 0.925 0.47)
			(stroke
				(width 0.05)
				(type default)
			)
			(fill no)
			(layer "F.CrtYd")
		)
		(fp_rect
			(start -0.5 -0.25)
			(end 0.5 0.25)
			(stroke
				(width 0.15)
				(type solid)
			)
			(fill no)
			(layer "F.Fab")
		)
		(pad "1" smd roundrect
			(at -0.48 0 180)
			(size 0.59 0.64)
			(layers "F.Cu" "F.Mask" "F.Paste")
			(roundrect_rratio 0.25)
			(net 398 "/FPGA Bank 14 & 15/SYSTEM_FLASH.DQ3")
			(pintype "passive")
		)
		(pad "2" smd roundrect
			(at 0.48 0 180)
			(size 0.59 0.64)
			(layers "F.Cu" "F.Mask" "F.Paste")
			(roundrect_rratio 0.25)
			(net 24 "+3V3")
			(pintype "passive")
		)
	)
	(footprint "antmicro-footprints:R_0402_1005Metric"
		(layer "F.Cu")
		(at 264.7 133.7 -90)
		(descr "Resistor SMD 0402")
		(tags "resistor SMD 0402")
		(property "Reference" "R153"
			(at -30.3 29.85 0)
			(layer "F.SilkS")
			(effects
				(font
					(size 0.7 0.7)
					(thickness 0.15)
				)
				(justify left bottom)
			)
		)
		(property "Value" "R_330R_0402"
			(at 0 1.4 270)
			(layer "F.Fab")
			(effects
				(font
					(size 0.7 0.7)
					(thickness 0.15)
				)
				(justify left bottom)
			)
		)
		(property "Description" "SMD Chip Resistor, 330 ohm, ± 1%, 62.5 mW, 0402 [1005 Metric], Thick Film, General Purpose"
			(at 0 0 270)
			(layer "F.Fab")
			(hide yes)
			(effects
				(font
					(size 1.27 1.27)
					(thickness 0.15)
				)
			)
		)
		(property "Author" "Antmicro"
			(at 131 398.4 0)
			(layer "F.Fab")
			(hide yes)
			(effects
				(font
					(size 1 1)
					(thickness 0.15)
				)
			)
		)
		(property "License" "Apache-2.0"
			(at 131 398.4 0)
			(layer "F.Fab")
			(hide yes)
			(effects
				(font
					(size 1 1)
					(thickness 0.15)
				)
			)
		)
		(property "MPN" "CR0402-FX-3300GLF"
			(at 131 398.4 0)
			(layer "F.Fab")
			(hide yes)
			(effects
				(font
					(size 1 1)
					(thickness 0.15)
				)
			)
		)
		(property "Manufacturer" "Bourns"
			(at 131 398.4 0)
			(layer "F.Fab")
			(hide yes)
			(effects
				(font
					(size 1 1)
					(thickness 0.15)
				)
			)
		)
		(property "Tolerance" "1%"
			(at 131 398.4 0)
			(layer "F.Fab")
			(hide yes)
			(effects
				(font
					(size 1 1)
					(thickness 0.15)
				)
			)
		)
		(property "Val" "330R"
			(at 131 398.4 0)
			(layer "F.Fab")
			(hide yes)
			(effects
				(font
					(size 1 1)
					(thickness 0.15)
				)
			)
		)
		(sheetname "USB PHY")
		(sheetfile "usb-phy.kicad_sch")
		(attr smd)
		(fp_rect
			(start -0.925 -0.47)
			(end 0.925 0.47)
			(stroke
				(width 0.05)
				(type default)
			)
			(fill no)
			(layer "F.CrtYd")
		)
		(fp_rect
			(start -0.5 -0.25)
			(end 0.5 0.25)
			(stroke
				(width 0.15)
				(type solid)
			)
			(fill no)
			(layer "F.Fab")
		)
		(pad "1" smd roundrect
			(at -0.48 0 270)
			(size 0.59 0.64)
			(layers "F.Cu" "F.Mask" "F.Paste")
			(roundrect_rratio 0.25)
			(net 793 "Net-(D29-A)")
			(pintype "passive")
		)
		(pad "2" smd roundrect
			(at 0.48 0 270)
			(size 0.59 0.64)
			(layers "F.Cu" "F.Mask" "F.Paste")
			(roundrect_rratio 0.25)
			(net 915 "/USB PHY/LED_RX1")
			(pintype "passive")
		)
	)
	(footprint "antmicro-footprints:R_0402_1005Metric"
		(layer "F.Cu")
		(at 210.81 75.44 -90)
		(descr "Resistor SMD 0402")
		(tags "resistor SMD 0402")
		(property "Reference" "R10"
			(at -0.74 -0.39 270)
			(layer "F.SilkS")
			(effects
				(font
					(size 0.7 0.7)
					(thickness 0.15)
				)
				(justify left bottom)
			)
		)
		(property "Value" "R_330R_0402"
			(at 0 1.4 270)
			(layer "F.Fab")
			(effects
				(font
					(size 0.7 0.7)
					(thickness 0.15)
				)
				(justify left bottom)
			)
		)
		(property "Description" "SMD Chip Resistor, 330 ohm, ± 1%, 62.5 mW, 0402 [1005 Metric], Thick Film, General Purpose"
			(at 0 0 270)
			(layer "F.Fab")
			(hide yes)
			(effects
				(font
					(size 1.27 1.27)
					(thickness 0.15)
				)
			)
		)
		(property "Author" "Antmicro"
			(at 135.37 286.25 0)
			(layer "F.Fab")
			(hide yes)
			(effects
				(font
					(size 1 1)
					(thickness 0.15)
				)
			)
		)
		(property "License" "Apache-2.0"
			(at 135.37 286.25 0)
			(layer "F.Fab")
			(hide yes)
			(effects
				(font
					(size 1 1)
					(thickness 0.15)
				)
			)
		)
		(property "MPN" "CR0402-FX-3300GLF"
			(at 135.37 286.25 0)
			(layer "F.Fab")
			(hide yes)
			(effects
				(font
					(size 1 1)
					(thickness 0.15)
				)
			)
		)
		(property "Manufacturer" "Bourns"
			(at 135.37 286.25 0)
			(layer "F.Fab")
			(hide yes)
			(effects
				(font
					(size 1 1)
					(thickness 0.15)
				)
			)
		)
		(property "Tolerance" "1%"
			(at 135.37 286.25 0)
			(layer "F.Fab")
			(hide yes)
			(effects
				(font
					(size 1 1)
					(thickness 0.15)
				)
			)
		)
		(property "Val" "330R"
			(at 135.37 286.25 0)
			(layer "F.Fab")
			(hide yes)
			(effects
				(font
					(size 1 1)
					(thickness 0.15)
				)
			)
		)
		(sheetname "FPGA Config")
		(sheetfile "fpga-config.kicad_sch")
		(attr smd)
		(fp_rect
			(start -0.925 -0.47)
			(end 0.925 0.47)
			(stroke
				(width 0.05)
				(type default)
			)
			(fill no)
			(layer "F.CrtYd")
		)
		(fp_rect
			(start -0.5 -0.25)
			(end 0.5 0.25)
			(stroke
				(width 0.15)
				(type solid)
			)
			(fill no)
			(layer "F.Fab")
		)
		(pad "1" smd roundrect
			(at -0.48 0 270)
			(size 0.59 0.64)
			(layers "F.Cu" "F.Mask" "F.Paste")
			(roundrect_rratio 0.25)
			(net 754 "Net-(D2-C)")
			(pintype "passive")
		)
		(pad "2" smd roundrect
			(at 0.48 0 270)
			(size 0.59 0.64)
			(layers "F.Cu" "F.Mask" "F.Paste")
			(roundrect_rratio 0.25)
			(net 336 "Net-(Q2-D)")
			(pintype "passive")
		)
	)
	(footprint "antmicro-footprints:PinHeader_2x7_P2mm_SMD_Shrouded_no-locator"
		(layer "F.Cu")
		(at 189.000001 74.000001 180)
		(descr "Pin Header 2x7 SMD Shrouded no-locator")
		(property "Reference" "J1"
			(at 8.800001 -4.399999 180)
			(layer "F.SilkS")
			(effects
				(font
					(size 0.7 0.7)
					(thickness 0.15)
				)
				(justify left bottom)
			)
		)
		(property "Value" "PinHeader_2x7_P2mm_SMD_Shrouded_no-locator"
			(at 0 5.038 180)
			(layer "F.Fab")
			(effects
				(font
					(size 0.7 0.7)
					(thickness 0.15)
				)
				(justify left bottom)
			)
		)
		(property "Author" "Antmicro"
			(at 378.000002 148.000002 0)
			(layer "F.Fab")
			(hide yes)
			(effects
				(font
					(size 1 1)
					(thickness 0.15)
				)
			)
		)
		(property "License" "Apache-2.0"
			(at 378.000002 148.000002 0)
			(layer "F.Fab")
			(hide yes)
			(effects
				(font
					(size 1 1)
					(thickness 0.15)
				)
			)
		)
		(property "MPN" "878321412"
			(at 378.000002 148.000002 0)
			(layer "F.Fab")
			(hide yes)
			(effects
				(font
					(size 1 1)
					(thickness 0.15)
				)
			)
		)
		(property "Manufacturer" "Molex"
			(at 378.000002 148.000002 0)
			(layer "F.Fab")
			(hide yes)
			(effects
				(font
					(size 1 1)
					(thickness 0.15)
				)
			)
		)
		(sheetname "FPGA Config")
		(sheetfile "fpga-config.kicad_sch")
		(attr smd)
		(fp_line
			(start 8.499 3.297)
			(end 8.499 2.797)
			(stroke
				(width 0.15)
				(type solid)
			)
			(layer "F.SilkS")
		)
		(fp_line
			(start 8.499 3.297)
			(end 7.998 3.297)
			(stroke
				(width 0.15)
				(type solid)
			)
			(layer "F.SilkS")
		)
		(fp_line
			(start 8.499 -3.301)
			(end 8.499 -2.801)
			(stroke
				(width 0.15)
				(type solid)
			)
			(layer "F.SilkS")
		)
		(fp_line
			(start 8.499 -3.301)
			(end 7.998 -3.301)
			(stroke
				(width 0.15)
				(type solid)
			)
			(layer "F.SilkS")
		)
		(fp_line
			(start 1.394 2.418)
			(end 1.394 2.918)
			(stroke
				(width 0.15)
				(type solid)
			)
			(layer "F.SilkS")
		)
		(fp_line
			(start 1.394 2.418)
			(end 0.897 2.418)
			(stroke
				(width 0.15)
				(type solid)
			)
			(layer "F.SilkS")
		)
		(fp_line
			(start -1.397 2.41)
			(end -0.9 2.41)
			(stroke
				(width 0.15)
				(type solid)
			)
			(layer "F.SilkS")
		)
		(fp_line
			(start -1.397 2.41)
			(end -1.397 2.91)
			(stroke
				(width 0.15)
				(type solid)
			)
			(layer "F.SilkS")
		)
		(fp_line
			(start -8.5 3.297)
			(end -8 3.297)
			(stroke
				(width 0.15)
				(type solid)
			)
			(layer "F.SilkS")
		)
		(fp_line
			(start -8.5 3.297)
			(end -8.5 2.797)
			(stroke
				(width 0.15)
				(type solid)
			)
			(layer "F.SilkS")
		)
		(fp_line
			(start -8.5 -3.301)
			(end -8 -3.301)
			(stroke
				(width 0.15)
				(type solid)
			)
			(layer "F.SilkS")
		)
		(fp_line
			(start -8.5 -3.301)
			(end -8.5 -2.801)
			(stroke
				(width 0.15)
				(type solid)
			)
			(layer "F.SilkS")
		)
		(fp_circle
			(center -6.8 3.4)
			(end -6.748 3.4)
			(stroke
				(width 0.15)
				(type solid)
			)
			(fill yes)
			(layer "F.SilkS")
		)
		(fp_rect
			(start -8.7 -3.7)
			(end 8.7 3.7)
			(stroke
				(width 0.05)
				(type solid)
			)
			(fill no)
			(layer "F.CrtYd")
		)
		(fp_line
			(start 8.323 3.148)
			(end 8.323 -3.15)
			(stroke
				(width 0.15)
				(type solid)
			)
			(layer "F.Fab")
		)
		(fp_line
			(start 1.394 3.148)
			(end 8.323 3.148)
			(stroke
				(width 0.15)
				(type solid)
			)
			(layer "F.Fab")
		)
		(fp_line
			(start 1.394 2.41)
			(end 1.394 3.14)
			(stroke
				(width 0.15)
				(type solid)
			)
			(layer "F.Fab")
		)
		(fp_line
			(start -1.397 2.41)
			(end 1.394 2.41)
			(stroke
				(width 0.15)
				(type solid)
			)
			(layer "F.Fab")
		)
		(fp_line
			(start -1.397 2.41)
			(end -1.397 3.14)
			(stroke
				(width 0.15)
				(type solid)
			)
			(layer "F.Fab")
		)
		(fp_line
			(start -8.325 3.148)
			(end -1.397 3.148)
			(stroke
				(width 0.15)
				(type solid)
			)
			(layer "F.Fab")
		)
		(fp_line
			(start -8.325 3.148)
			(end -8.325 -3.15)
			(stroke
				(width 0.15)
				(type solid)
			)
			(layer "F.Fab")
		)
		(fp_line
			(start -8.325 -3.15)
			(end 8.323 -3.15)
			(stroke
				(width 0.15)
				(type solid)
			)
			(layer "F.Fab")
		)
		(pad "1" smd rect
			(at -6 2.128 180)
			(size 1 2.75)
			(layers "F.Cu" "F.Mask" "F.Paste")
			(net 1 "GND")
			(pintype "passive")
		)
		(pad "2" smd rect
			(at -6 -2.13 180)
			(size 1 2.75)
			(layers "F.Cu" "F.Mask" "F.Paste")
			(net 24 "+3V3")
			(pintype "passive")
		)
		(pad "3" smd rect
			(at -4 2.128 180)
			(size 1 2.75)
			(layers "F.Cu" "F.Mask" "F.Paste")
			(net 1 "GND")
			(pintype "passive")
		)
		(pad "4" smd rect
			(at -4 -2.13 180)
			(size 1 2.75)
			(layers "F.Cu" "F.Mask" "F.Paste")
			(net 161 "/FPGA Config/JTAG.TMS")
			(pintype "passive")
		)
		(pad "5" smd rect
			(at -2 2.128 180)
			(size 1 2.75)
			(layers "F.Cu" "F.Mask" "F.Paste")
			(net 1 "GND")
			(pintype "passive")
		)
		(pad "6" smd rect
			(at -2 -2.13 180)
			(size 1 2.75)
			(layers "F.Cu" "F.Mask" "F.Paste")
			(net 165 "/FPGA Config/JTAG.TCK")
			(pintype "passive")
		)
		(pad "7" smd rect
			(at 0 2.128 180)
			(size 1 2.75)
			(layers "F.Cu" "F.Mask" "F.Paste")
			(net 1 "GND")
			(pintype "passive")
		)
		(pad "8" smd rect
			(at 0 -2.13 180)
			(size 1 2.75)
			(layers "F.Cu" "F.Mask" "F.Paste")
			(net 190 "/FPGA Config/JTAG.TDO")
			(pintype "passive")
		)
		(pad "9" smd rect
			(at 1.999 2.128 180)
			(size 1 2.75)
			(layers "F.Cu" "F.Mask" "F.Paste")
			(net 1 "GND")
			(pintype "passive")
		)
		(pad "10" smd rect
			(at 1.999 -2.13 180)
			(size 1 2.75)
			(layers "F.Cu" "F.Mask" "F.Paste")
			(net 220 "/FPGA Config/JTAG.TDI")
			(pintype "passive")
		)
		(pad "11" smd rect
			(at 3.999 2.128 180)
			(size 1 2.75)
			(layers "F.Cu" "F.Mask" "F.Paste")
			(net 1 "GND")
			(pintype "passive")
		)
		(pad "12" smd rect
			(at 3.999 -2.13 180)
			(size 1 2.75)
			(layers "F.Cu" "F.Mask" "F.Paste")
			(net 431 "/FPGA Config/JTAG.RST")
			(pintype "passive")
		)
		(pad "13" smd rect
			(at 5.998 2.128 180)
			(size 1 2.75)
			(layers "F.Cu" "F.Mask" "F.Paste")
			(net 1 "GND")
			(pintype "passive")
		)
		(pad "14" smd rect
			(at 5.998 -2.13 180)
			(size 1 2.75)
			(layers "F.Cu" "F.Mask" "F.Paste")
			(net 799 "FTDI_DIS")
			(pintype "passive")
		)
	)
	(footprint "antmicro-footprints:R_0402_1005Metric"
		(layer "F.Cu")
		(at 235.9 114.575)
		(descr "Resistor SMD 0402")
		(tags "resistor SMD 0402")
		(property "Reference" "R97"
			(at 0.8 0.325 0)
			(layer "F.SilkS")
			(effects
				(font
					(size 0.7 0.7)
					(thickness 0.15)
				)
				(justify left bottom)
			)
		)
		(property "Value" "R_100R_0402"
			(at 0 1.4 0)
			(layer "F.Fab")
			(effects
				(font
					(size 0.7 0.7)
					(thickness 0.15)
				)
				(justify left bottom)
			)
		)
		(property "Description" "SMD Chip Resistor, 100 ohm, ± 1%, 62.5 mW, 0402 [1005 Metric], Thick Film, General Purpose"
			(at 0 0 0)
			(layer "F.Fab")
			(hide yes)
			(effects
				(font
					(size 1.27 1.27)
					(thickness 0.15)
				)
			)
		)
		(property "Author" "Antmicro"
			(at 0 0 0)
			(layer "F.Fab")
			(hide yes)
			(effects
				(font
					(size 1 1)
					(thickness 0.15)
				)
			)
		)
		(property "DNP" "DNP"
			(at 0 0 0)
			(layer "F.Fab")
			(hide yes)
			(effects
				(font
					(size 1 1)
					(thickness 0.15)
				)
			)
		)
		(property "License" "Apache-2.0"
			(at 0 0 0)
			(layer "F.Fab")
			(hide yes)
			(effects
				(font
					(size 1 1)
					(thickness 0.15)
				)
			)
		)
		(property "MPN" "CR0402-FX-1000GLF"
			(at 0 0 0)
			(layer "F.Fab")
			(hide yes)
			(effects
				(font
					(size 1 1)
					(thickness 0.15)
				)
			)
		)
		(property "Manufacturer" "Bourns"
			(at 0 0 0)
			(layer "F.Fab")
			(hide yes)
			(effects
				(font
					(size 1 1)
					(thickness 0.15)
				)
			)
		)
		(property "Tolerance" "1%"
			(at 0 0 0)
			(layer "F.Fab")
			(hide yes)
			(effects
				(font
					(size 1 1)
					(thickness 0.15)
				)
			)
		)
		(property "Val" "100R"
			(at 0 0 0)
			(layer "F.Fab")
			(hide yes)
			(effects
				(font
					(size 1 1)
					(thickness 0.15)
				)
			)
		)
		(property "dnp" ""
			(at 0 0 0)
			(layer "F.Fab")
			(hide yes)
			(effects
				(font
					(size 1 1)
					(thickness 0.15)
				)
			)
		)
		(property "exclude_from_bom" ""
			(at 0 0 0)
			(layer "F.Fab")
			(hide yes)
			(effects
				(font
					(size 1 1)
					(thickness 0.15)
				)
			)
		)
		(sheetname "SPI Flash + SD Card")
		(sheetfile "spi-flash.kicad_sch")
		(attr smd exclude_from_bom)
		(fp_rect
			(start -0.925 -0.47)
			(end 0.925 0.47)
			(stroke
				(width 0.05)
				(type default)
			)
			(fill no)
			(layer "F.CrtYd")
		)
		(fp_rect
			(start -0.5 -0.25)
			(end 0.5 0.25)
			(stroke
				(width 0.15)
				(type solid)
			)
			(fill no)
			(layer "F.Fab")
		)
		(pad "1" smd roundrect
			(at -0.48 0)
			(size 0.59 0.64)
			(layers "F.Cu" "F.Mask" "F.Paste")
			(roundrect_rratio 0.25)
			(net 1 "GND")
			(pintype "passive")
		)
		(pad "2" smd roundrect
			(at 0.48 0)
			(size 0.59 0.64)
			(layers "F.Cu" "F.Mask" "F.Paste")
			(roundrect_rratio 0.25)
			(net 427 "/FPGA Bank 16 & 17/USR_FLASH_1.CLK")
			(pintype "passive")
		)
	)
)
